# T6G (Grand Teton) — schematic netlist excerpt (pin names and nets, part order shuffled) for the footprints in the layout excerpt that follows; sources: Cadence DE-HDL packaged netlist, KiCad conversion of 04192023_DAF0TMB3IC0_F0TG_MB_C_brd_V02_OCP.brd

R883  Q_RES  4.7K 5% CHIP  pkg 0201LF  page 342 : A = TEST2_RT_CPU1_P2 ; B = GND
R6182  Q_RES  4.7K 5% CHIP  pkg 0402LF  page 171 : A = P3V3_AUX ; B = PU_U160_EN_N
R3659  Q_RES  10K 1% EMPTY  pkg 0402LF  page 234 : A = P3V3_AUX ; B = USB_HUB_OVCUR4

(kicad_pcb
	(version 20260206)
	(generator "pcbnew")
	(generator_version "10.0")
	(general
		(thickness 1.6)
		(legacy_teardrops no)
	)
	(paper "A4")
	(title_block
		(title "04192023_DAF0TMB3IC0_F0TG_MB_C_brd_V02_OCP.brd")
		(comment 1 "Grand Teton / footprints 2784-2786 of 8354")
	)
	(layers
		(0 "F.Cu" signal "TOP")
		(4 "In1.Cu" signal "GND")
		(6 "In2.Cu" signal "IN1")
		(8 "In3.Cu" signal "GND1")
		(10 "In4.Cu" signal "IN2")
		(12 "In5.Cu" signal "GND2")
		(14 "In6.Cu" signal "IN3")
		(16 "In7.Cu" signal "GND3")
		(18 "In8.Cu" signal "VCC")
		(20 "In9.Cu" signal "VCC1")
		(22 "In10.Cu" signal "GND4")
		(24 "In11.Cu" signal "IN4")
		(26 "In12.Cu" signal "GND5")
		(28 "In13.Cu" signal "IN5")
		(30 "In14.Cu" signal "GND6")
		(32 "In15.Cu" signal "IN6")
		(34 "In16.Cu" signal "GND7")
		(2 "B.Cu" signal "BOTTOM")
		(9 "F.Adhes" user "F.Adhesive")
		(11 "B.Adhes" user "B.Adhesive")
		(13 "F.Paste" user "Package Geometry/Pastemask Top")
		(15 "B.Paste" user "Package Geometry/Pastemask Bottom")
		(5 "F.SilkS" user "Ref Des/Silkscreen Top")
		(7 "B.SilkS" user "Ref Des/Silkscreen Bottom")
		(1 "F.Mask" user "Board Geometry/Soldermask Top")
		(3 "B.Mask" user "Board Geometry/Soldermask Bottom")
		(17 "Dwgs.User" user "User.Drawings")
		(19 "Cmts.User" user "User.Comments")
		(21 "Eco1.User" user "User.Eco1")
		(23 "Eco2.User" user "User.Eco2")
		(25 "Edge.Cuts" user "Board Geometry/Outline")
		(27 "Margin" user)
		(31 "F.CrtYd" user "Package Geometry/Place Bound Top")
		(29 "B.CrtYd" user "Package Geometry/Place Bound Bottom")
		(35 "F.Fab" user "Ref Des/Assembly Top")
		(33 "B.Fab" user "Ref Des/Assembly Bottom")
	)
	(footprint ""
		(layer "F.Cu")
		(at 29.214064 -80.424274 -90)
		(property "Reference" "R6182"
			(at 0 0 270)
			(layer "F.SilkS")
			(hide yes)
			(effects
				(font
					(size 1.27 1.27)
				)
			)
		)
		(property "Value" ""
			(at 0 0 270)
			(layer "F.Fab")
			(effects
				(font
					(size 1.27 1.27)
				)
			)
		)
		(duplicate_pad_numbers_are_jumpers no)
		(fp_line
			(start -0.7874 0.4064)
			(end -0.7874 -0.4064)
			(stroke
				(width 0.1524)
				(type default)
			)
			(layer "F.SilkS")
		)
		(fp_line
			(start 0.7874 0.4064)
			(end -0.7874 0.4064)
			(stroke
				(width 0.1524)
				(type default)
			)
			(layer "F.SilkS")
		)
		(fp_line
			(start -0.7874 -0.4064)
			(end 0.7874 -0.4064)
			(stroke
				(width 0.1524)
				(type default)
			)
			(layer "F.SilkS")
		)
		(fp_line
			(start 0.7874 -0.4064)
			(end 0.7874 0.4064)
			(stroke
				(width 0.1524)
				(type default)
			)
			(layer "F.SilkS")
		)
		(fp_line
			(start -0.67945 0.3048)
			(end -0.67945 -0.305054)
			(stroke
				(width 0.1)
				(type default)
			)
			(layer "F.Fab")
		)
		(fp_line
			(start -0.12065 0.3048)
			(end -0.67945 0.3048)
			(stroke
				(width 0.1)
				(type default)
			)
			(layer "F.Fab")
		)
		(fp_line
			(start 0.120396 0.3048)
			(end 0.120396 0.2794)
			(stroke
				(width 0.1)
				(type default)
			)
			(layer "F.Fab")
		)
		(fp_line
			(start 0.67945 0.3048)
			(end 0.120396 0.3048)
			(stroke
				(width 0.1)
				(type default)
			)
			(layer "F.Fab")
		)
		(fp_line
			(start -0.12065 0.2794)
			(end -0.12065 0.3048)
			(stroke
				(width 0.1)
				(type default)
			)
			(layer "F.Fab")
		)
		(fp_line
			(start 0.120396 0.2794)
			(end -0.12065 0.2794)
			(stroke
				(width 0.1)
				(type default)
			)
			(layer "F.Fab")
		)
		(fp_line
			(start -0.12065 -0.2794)
			(end 0.12065 -0.2794)
			(stroke
				(width 0.1)
				(type default)
			)
			(layer "F.Fab")
		)
		(fp_line
			(start 0.12065 -0.2794)
			(end 0.12065 -0.3048)
			(stroke
				(width 0.1)
				(type default)
			)
			(layer "F.Fab")
		)
		(fp_line
			(start 0.12065 -0.3048)
			(end 0.67945 -0.3048)
			(stroke
				(width 0.1)
				(type default)
			)
			(layer "F.Fab")
		)
		(fp_line
			(start 0.67945 -0.3048)
			(end 0.67945 0.3048)
			(stroke
				(width 0.1)
				(type default)
			)
			(layer "F.Fab")
		)
		(fp_line
			(start -0.67945 -0.305054)
			(end -0.12065 -0.305054)
			(stroke
				(width 0.1)
				(type default)
			)
			(layer "F.Fab")
		)
		(fp_line
			(start -0.12065 -0.305054)
			(end -0.12065 -0.2794)
			(stroke
				(width 0.1)
				(type default)
			)
			(layer "F.Fab")
		)
		(pad "1" smd circle
			(at -0.40005 0 270)
			(size 0 0)
			(layers "F.Cu" "F.Mask" "F.Paste")
			(net "P3V3_AUX")
		)
		(pad "2" smd circle
			(at 0.40005 0 270)
			(size 0 0)
			(layers "F.Cu" "F.Mask" "F.Paste")
			(net "PU_U160_EN_N")
		)
	)
	(footprint ""
		(layer "F.Cu")
		(at 142.893542 -383.7432)
		(property "Reference" "R883"
			(at 0 0 0)
			(layer "F.SilkS")
			(hide yes)
			(effects
				(font
					(size 1.27 1.27)
				)
			)
		)
		(property "Value" ""
			(at 0 0 0)
			(layer "F.Fab")
			(effects
				(font
					(size 1.27 1.27)
				)
			)
		)
		(duplicate_pad_numbers_are_jumpers no)
		(fp_line
			(start -0.32512 -0.175006)
			(end 0.32512 -0.175006)
			(stroke
				(width 0.1)
				(type default)
			)
			(layer "F.Fab")
		)
		(fp_line
			(start -0.32512 0.175006)
			(end -0.32512 -0.175006)
			(stroke
				(width 0.1)
				(type default)
			)
			(layer "F.Fab")
		)
		(fp_line
			(start 0.32512 -0.175006)
			(end 0.32512 0.175006)
			(stroke
				(width 0.1)
				(type default)
			)
			(layer "F.Fab")
		)
		(fp_line
			(start 0.32512 0.175006)
			(end -0.32512 0.175006)
			(stroke
				(width 0.1)
				(type default)
			)
			(layer "F.Fab")
		)
		(pad "1" smd rect
			(at -0.2667 0)
			(size 0.3048 0.381)
			(layers "F.Cu" "F.Mask" "F.Paste")
			(net "TEST2_RT_CPU1_P2")
		)
		(pad "2" smd rect
			(at 0.2667 0 180)
			(size 0.3048 0.381)
			(layers "F.Cu" "F.Mask" "F.Paste")
			(net "GND")
		)
	)
	(footprint ""
		(layer "F.Cu")
		(at 15.067788 -92.687648 90)
		(property "Reference" "R3659"
			(at 0 0 90)
			(layer "F.SilkS")
			(hide yes)
			(effects
				(font
					(size 1.27 1.27)
				)
			)
		)
		(property "Value" ""
			(at 0 0 90)
			(layer "F.Fab")
			(effects
				(font
					(size 1.27 1.27)
				)
			)
		)
		(duplicate_pad_numbers_are_jumpers no)
		(fp_line
			(start 0.7874 -0.4064)
			(end 0.7874 0.4064)
			(stroke
				(width 0.1524)
				(type default)
			)
			(layer "F.SilkS")
		)
		(fp_line
			(start -0.7874 -0.4064)
			(end 0.7874 -0.4064)
			(stroke
				(width 0.1524)
				(type default)
			)
			(layer "F.SilkS")
		)
		(fp_line
			(start 0.7874 0.4064)
			(end -0.7874 0.4064)
			(stroke
				(width 0.1524)
				(type default)
			)
			(layer "F.SilkS")
		)
		(fp_line
			(start -0.7874 0.4064)
			(end -0.7874 -0.4064)
			(stroke
				(width 0.1524)
				(type default)
			)
			(layer "F.SilkS")
		)
		(fp_line
			(start -0.12065 -0.305054)
			(end -0.12065 -0.2794)
			(stroke
				(width 0.1)
				(type default)
			)
			(layer "F.Fab")
		)
		(fp_line
			(start -0.67945 -0.305054)
			(end -0.12065 -0.305054)
			(stroke
				(width 0.1)
				(type default)
			)
			(layer "F.Fab")
		)
		(fp_line
			(start 0.67945 -0.3048)
			(end 0.67945 0.3048)
			(stroke
				(width 0.1)
				(type default)
			)
			(layer "F.Fab")
		)
		(fp_line
			(start 0.12065 -0.3048)
			(end 0.67945 -0.3048)
			(stroke
				(width 0.1)
				(type default)
			)
			(layer "F.Fab")
		)
		(fp_line
			(start 0.12065 -0.2794)
			(end 0.12065 -0.3048)
			(stroke
				(width 0.1)
				(type default)
			)
			(layer "F.Fab")
		)
		(fp_line
			(start -0.12065 -0.2794)
			(end 0.12065 -0.2794)
			(stroke
				(width 0.1)
				(type default)
			)
			(layer "F.Fab")
		)
		(fp_line
			(start 0.120396 0.2794)
			(end -0.12065 0.2794)
			(stroke
				(width 0.1)
				(type default)
			)
			(layer "F.Fab")
		)
		(fp_line
			(start -0.12065 0.2794)
			(end -0.12065 0.3048)
			(stroke
				(width 0.1)
				(type default)
			)
			(layer "F.Fab")
		)
		(fp_line
			(start 0.67945 0.3048)
			(end 0.120396 0.3048)
			(stroke
				(width 0.1)
				(type default)
			)
			(layer "F.Fab")
		)
		(fp_line
			(start 0.120396 0.3048)
			(end 0.120396 0.2794)
			(stroke
				(width 0.1)
				(type default)
			)
			(layer "F.Fab")
		)
		(fp_line
			(start -0.12065 0.3048)
			(end -0.67945 0.3048)
			(stroke
				(width 0.1)
				(type default)
			)
			(layer "F.Fab")
		)
		(fp_line
			(start -0.67945 0.3048)
			(end -0.67945 -0.305054)
			(stroke
				(width 0.1)
				(type default)
			)
			(layer "F.Fab")
		)
		(pad "1" smd circle
			(at -0.40005 0 90)
			(size 0 0)
			(layers "F.Cu" "F.Mask" "F.Paste")
			(net "P3V3_AUX")
		)
		(pad "2" smd circle
			(at 0.40005 0 90)
			(size 0 0)
			(layers "F.Cu" "F.Mask" "F.Paste")
			(net "USB_HUB_OVCUR4")
		)
	)
)
